# TIMECARD (Time Appliance Project (Time Card)) — schematic netlist excerpt (pin names and nets, part order shuffled) for the footprints in the layout excerpt that follows; sources: Cadence DE-HDL packaged netlist, KiCad conversion of R4006-B0001-02_R01.brd

TP37  TP_PIONT  pkg TP010CT020B030_PTH  page 25 : \1\ = XP12R0V_A_FLTB
TP24  TP_PIONT  pkg TP010CT020B030_PTH  page 25 : \1\ = FPGA_IN_LM75B_INT1_N
TP30  TP_PIONT  pkg TP010CT020B030_PTH  page 25 : \1\ = SMA3_SIG_IN_BF_EN_N
R346  RESISTOR  0OHM -  pkg SMC_0402R_H016  page 19 : \1\ = UNNAMED_8_ICP10100LGA10_I24_R_1 ; \2\ = SG

(kicad_pcb
	(version 20260206)
	(generator "pcbnew")
	(generator_version "10.0")
	(general
		(thickness 1.6)
		(legacy_teardrops no)
	)
	(paper "A4")
	(title_block
		(title "timecard-production-celestica-r4006 — R4006-B0001-02_R01.brd")
		(comment 1 "Time Appliance Project (Time Card) / footprints 136-139 of 1113")
	)
	(layers
		(0 "F.Cu" signal "TOP")
		(4 "In1.Cu" signal "L02_GND1")
		(6 "In2.Cu" signal "L03_SIG1")
		(8 "In3.Cu" signal "L04_GND2")
		(10 "In4.Cu" signal "L05_VCC1")
		(12 "In5.Cu" signal "L06_VCC2")
		(14 "In6.Cu" signal "L07_GND3")
		(16 "In7.Cu" signal "L08_SIG2")
		(18 "In8.Cu" signal "L09_GND4")
		(2 "B.Cu" signal "BOTTOM")
		(9 "F.Adhes" user "F.Adhesive")
		(11 "B.Adhes" user "B.Adhesive")
		(13 "F.Paste" user "Package Geometry/Pastemask Top")
		(15 "B.Paste" user "Package Geometry/Pastemask Bottom")
		(5 "F.SilkS" user "Ref Des/Silkscreen Top")
		(7 "B.SilkS" user "Ref Des/Silkscreen Bottom")
		(1 "F.Mask" user "Board Geometry/Soldermask Top")
		(3 "B.Mask" user "Board Geometry/Soldermask Bottom")
		(17 "Dwgs.User" user "User.Drawings")
		(19 "Cmts.User" user "User.Comments")
		(21 "Eco1.User" user "User.Eco1")
		(23 "Eco2.User" user "User.Eco2")
		(25 "Edge.Cuts" user "Board Geometry/Outline")
		(27 "Margin" user)
		(31 "F.CrtYd" user "Package Geometry/Place Bound Top")
		(29 "B.CrtYd" user "Package Geometry/Place Bound Bottom")
		(35 "F.Fab" user "Ref Des/Assembly Top")
		(33 "B.Fab" user "Ref Des/Assembly Bottom")
	)
	(footprint ""
		(layer "F.Cu")
		(at 16.256 -70.866 180)
		(property "Reference" "R346"
			(at -0.381 1.73863 0)
			(unlocked yes)
			(layer "F.SilkS")
			(effects
				(font
					(size 0.7874 0.5842)
					(thickness 0.1524)
				)
			)
		)
		(property "Value" "VAL*"
			(at 0.02032 2.13233 180)
			(unlocked yes)
			(layer "F.Fab")
			(hide yes)
			(effects
				(font
					(size 0.7874 0.5842)
					(thickness 0.1524)
				)
			)
		)
		(property "Tolerance" "TOL*"
			(at 0.044704 3.05435 180)
			(unlocked yes)
			(layer "Cmts.User")
			(hide yes)
			(effects
				(font
					(size 0.7874 0.5842)
					(thickness 0.1524)
				)
			)
		)
		(property "User Part Number" "PARTNUM*"
			(at 0.02032 4.024884 180)
			(unlocked yes)
			(layer "Cmts.User")
			(hide yes)
			(effects
				(font
					(size 0.7874 0.5842)
					(thickness 0.1524)
				)
			)
		)
		(property "Device Type" "RESISTOR-G155-100R0-J0,0OHM,-"
			(at 0.008382 1.210564 180)
			(unlocked yes)
			(layer "F.Fab")
			(hide yes)
			(effects
				(font
					(size 0.7874 0.5842)
					(thickness 0.1524)
				)
			)
		)
		(duplicate_pad_numbers_are_jumpers no)
		(fp_line
			(start 1.143 0.5588)
			(end 1.143 -0.5588)
			(stroke
				(width 0.1)
				(type default)
			)
			(layer "F.SilkS")
		)
		(fp_line
			(start 1.143 -0.5588)
			(end -1.143 -0.5588)
			(stroke
				(width 0.1)
				(type default)
			)
			(layer "F.SilkS")
		)
		(fp_line
			(start -1.143 0.5588)
			(end 1.143 0.5588)
			(stroke
				(width 0.1)
				(type default)
			)
			(layer "F.SilkS")
		)
		(fp_line
			(start -1.143 -0.5588)
			(end -1.143 0.5588)
			(stroke
				(width 0.1)
				(type default)
			)
			(layer "F.SilkS")
		)
		(fp_poly
			(pts
				(xy -1.143 0.5588) (xy 1.143 0.5588) (xy 1.143 -0.5588) (xy -1.143 -0.5588)
			)
			(stroke
				(width 0)
				(type default)
			)
			(fill no)
			(layer "F.CrtYd")
		)
		(fp_line
			(start 0.508 0.3048)
			(end 0.508 -0.3048)
			(stroke
				(width 0.1)
				(type default)
			)
			(layer "F.Fab")
		)
		(fp_line
			(start 0.508 -0.3048)
			(end -0.508 -0.3048)
			(stroke
				(width 0.1)
				(type default)
			)
			(layer "F.Fab")
		)
		(fp_line
			(start -0.508 0.3048)
			(end 0.508 0.3048)
			(stroke
				(width 0.1)
				(type default)
			)
			(layer "F.Fab")
		)
		(fp_line
			(start -0.508 -0.3048)
			(end -0.508 0.3048)
			(stroke
				(width 0.1)
				(type default)
			)
			(layer "F.Fab")
		)
		(pad "1" smd rect
			(at -0.5334 0 180)
			(size 0.7112 0.6096)
			(layers "F.Cu" "F.Mask" "F.Paste")
			(net "UNNAMED_8_ICP10100LGA10_I24_R_1")
		)
		(pad "2" smd rect
			(at 0.5334 0 180)
			(size 0.7112 0.6096)
			(layers "F.Cu" "F.Mask" "F.Paste")
			(net "SG")
		)
		(zone
			(layer "F.Cu")
			(hatch none 0.5)
			(connect_pads
				(clearance 0)
			)
			(min_thickness 0.25)
			(keepout
				(tracks allowed)
				(vias not_allowed)
				(pads allowed)
				(copperpour not_allowed)
				(footprints allowed)
			)
			(placement
				(enabled no)
				(sheetname "")
			)
			(fill
				(thermal_gap 0.5)
				(thermal_bridge_width 0.5)
				(island_removal_mode 0)
			)
			(polygon
				(pts
					(xy 16.3322 -71.1708) (xy 16.1798 -71.1708) (xy 16.1798 -70.5612) (xy 16.3322 -70.5612)
				)
			)
		)
		(zone
			(layer "F.Cu")
			(hatch none 0.5)
			(connect_pads
				(clearance 0)
			)
			(min_thickness 0.25)
			(keepout
				(tracks not_allowed)
				(vias allowed)
				(pads allowed)
				(copperpour not_allowed)
				(footprints allowed)
			)
			(placement
				(enabled no)
				(sheetname "")
			)
			(fill
				(thermal_gap 0.5)
				(thermal_bridge_width 0.5)
				(island_removal_mode 0)
			)
			(polygon
				(pts
					(xy 16.3322 -71.1708) (xy 16.1798 -71.1708) (xy 16.1798 -70.5612) (xy 16.3322 -70.5612)
				)
			)
		)
	)
	(footprint ""
		(layer "F.Cu")
		(at 16.1544 -74.041)
		(property "Reference" "TP24"
			(at -2.3876 -2.37363 0)
			(unlocked yes)
			(layer "F.SilkS")
			(effects
				(font
					(size 0.7874 0.5842)
					(thickness 0.1524)
				)
				(justify left)
			)
		)
		(property "Value" ""
			(at 0 0 0)
			(layer "F.Fab")
			(effects
				(font
					(size 1.27 1.27)
				)
			)
		)
		(property "Device Type" "TP_PIONT-TP010CT020B030_PTH-TPA"
			(at -1.341882 0.996696 0)
			(unlocked yes)
			(layer "F.Fab")
			(hide yes)
			(effects
				(font
					(size 0.7874 0.5842)
					(thickness 0.000001)
				)
				(justify left)
			)
		)
		(duplicate_pad_numbers_are_jumpers no)
		(fp_poly
			(pts
				(arc
					(start 0.889 0)
					(mid -0.889 0)
					(end 0.889 0)
				)
			)
			(stroke
				(width 0)
				(type default)
			)
			(fill no)
			(layer "B.CrtYd")
		)
		(fp_poly
			(pts
				(arc
					(start 0.889 0)
					(mid -0.889 0)
					(end 0.889 0)
				)
			)
			(stroke
				(width 0)
				(type default)
			)
			(fill no)
			(layer "F.CrtYd")
		)
		(pad "1" thru_hole circle
			(at 0 0)
			(size 0.508 0.508)
			(drill 0.254)
			(layers "*.Cu" "*.Mask")
			(remove_unused_layers no)
			(net "FPGA_IN_LM75B_INT1_N")
			(clearance 0.1016)
			(padstack
				(mode front_inner_back)
				(layer "Inner"
					(shape circle)
					(size 0.508 0.508)
					(clearance 0.1016)
				)
				(layer "B.Cu"
					(shape circle)
					(size 0.762 0.762)
					(clearance -0.0254)
				)
			)
		)
	)
	(footprint ""
		(layer "F.Cu")
		(at 14.351 -28.702)
		(property "Reference" "TP30"
			(at -0.22225 2.5654 90)
			(unlocked yes)
			(layer "F.SilkS")
			(effects
				(font
					(size 0.635 0.4064)
					(thickness 0.1524)
				)
				(justify left)
			)
		)
		(property "Value" ""
			(at 0 0 0)
			(layer "F.Fab")
			(effects
				(font
					(size 1.27 1.27)
				)
			)
		)
		(property "Device Type" "TP_PIONT-TP010CT020B030_PTH-TPA"
			(at -1.341882 0.996696 0)
			(unlocked yes)
			(layer "F.Fab")
			(hide yes)
			(effects
				(font
					(size 0.7874 0.5842)
					(thickness 0.000001)
				)
				(justify left)
			)
		)
		(duplicate_pad_numbers_are_jumpers no)
		(fp_poly
			(pts
				(arc
					(start 0.889 0)
					(mid -0.889 0)
					(end 0.889 0)
				)
			)
			(stroke
				(width 0)
				(type default)
			)
			(fill no)
			(layer "B.CrtYd")
		)
		(fp_poly
			(pts
				(arc
					(start 0.889 0)
					(mid -0.889 0)
					(end 0.889 0)
				)
			)
			(stroke
				(width 0)
				(type default)
			)
			(fill no)
			(layer "F.CrtYd")
		)
		(pad "1" thru_hole circle
			(at 0 0)
			(size 0.508 0.508)
			(drill 0.254)
			(layers "*.Cu" "*.Mask")
			(remove_unused_layers no)
			(net "SMA3_SIG_IN_BF_EN_N")
			(clearance 0.1016)
			(padstack
				(mode front_inner_back)
				(layer "Inner"
					(shape circle)
					(size 0.508 0.508)
					(clearance 0.1016)
				)
				(layer "B.Cu"
					(shape circle)
					(size 0.762 0.762)
					(clearance -0.0254)
				)
			)
		)
	)
	(footprint ""
		(layer "F.Cu")
		(at 145.2372 -100.711)
		(property "Reference" "TP37"
			(at 1.4224 0.15875 0)
			(unlocked yes)
			(layer "F.SilkS")
			(effects
				(font
					(size 0.635 0.4064)
					(thickness 0.1524)
				)
				(justify left)
			)
		)
		(property "Value" ""
			(at 0 0 0)
			(layer "F.Fab")
			(effects
				(font
					(size 1.27 1.27)
				)
			)
		)
		(property "Device Type" "TP_PIONT-TP010CT020B030_PTH-TPA"
			(at -1.341882 0.996696 0)
			(unlocked yes)
			(layer "F.Fab")
			(hide yes)
			(effects
				(font
					(size 0.7874 0.5842)
					(thickness 0.000001)
				)
				(justify left)
			)
		)
		(duplicate_pad_numbers_are_jumpers no)
		(fp_poly
			(pts
				(arc
					(start 0.889 0)
					(mid -0.889 0)
					(end 0.889 0)
				)
			)
			(stroke
				(width 0)
				(type default)
			)
			(fill no)
			(layer "B.CrtYd")
		)
		(fp_poly
			(pts
				(arc
					(start 0.889 0)
					(mid -0.889 0)
					(end 0.889 0)
				)
			)
			(stroke
				(width 0)
				(type default)
			)
			(fill no)
			(layer "F.CrtYd")
		)
		(pad "1" thru_hole circle
			(at 0 0)
			(size 0.508 0.508)
			(drill 0.254)
			(layers "*.Cu" "*.Mask")
			(remove_unused_layers no)
			(net "XP12R0V_A_FLTB")
			(clearance 0.1016)
			(padstack
				(mode front_inner_back)
				(layer "Inner"
					(shape circle)
					(size 0.508 0.508)
					(clearance 0.1016)
				)
				(layer "B.Cu"
					(shape circle)
					(size 0.762 0.762)
					(clearance -0.0254)
				)
			)
		)
	)
)
